(kicad_pcb
	(version 20260206)
	(generator "pcbnew")
	(generator_version "10.0")
	(general
		(thickness 1.6)
		(legacy_teardrops no)
	)
	(paper "A4")
	(title_block
		(title "01162023_DA0F0TEBIF0_F0T_Expander_BD_F_brd_V02_OCP.brd")
		(comment 1 "Grand Teton / footprint 3855 of 9728 (J9), pads 78-142 of 142")
	)
	(layers
		(0 "F.Cu" signal "TOP")
		(4 "In1.Cu" signal "GND")
		(6 "In2.Cu" signal "VCC")
		(8 "In3.Cu" signal "VCC1")
		(10 "In4.Cu" signal "GND1")
		(12 "In5.Cu" signal "IN1")
		(14 "In6.Cu" signal "GND2")
		(16 "In7.Cu" signal "IN2")
		(18 "In8.Cu" signal "GND3")
		(20 "In9.Cu" signal "IN3")
		(22 "In10.Cu" signal "GND4")
		(24 "In11.Cu" signal "IN4")
		(26 "In12.Cu" signal "GND5")
		(28 "In13.Cu" signal "IN5")
		(30 "In14.Cu" signal "GND6")
		(32 "In15.Cu" signal "IN6")
		(34 "In16.Cu" signal "GND7")
		(2 "B.Cu" signal "BOTTOM")
		(9 "F.Adhes" user "F.Adhesive")
		(11 "B.Adhes" user "B.Adhesive")
		(13 "F.Paste" user "Package Geometry/Pastemask Top")
		(15 "B.Paste" user "Package Geometry/Pastemask Bottom")
		(5 "F.SilkS" user "Ref Des/Silkscreen Top")
		(7 "B.SilkS" user "Ref Des/Silkscreen Bottom")
		(1 "F.Mask" user "Board Geometry/Soldermask Top")
		(3 "B.Mask" user "Board Geometry/Soldermask Bottom")
		(17 "Dwgs.User" user "User.Drawings")
		(19 "Cmts.User" user "User.Comments")
		(21 "Eco1.User" user "User.Eco1")
		(23 "Eco2.User" user "User.Eco2")
		(25 "Edge.Cuts" user "Board Geometry/Outline")
		(27 "Margin" user)
		(31 "F.CrtYd" user "Package Geometry/Place Bound Top")
		(29 "B.CrtYd" user "Package Geometry/Place Bound Bottom")
		(35 "F.Fab" user "Ref Des/Assembly Top")
		(33 "B.Fab" user "Ref Des/Assembly Bottom")
	)
	(footprint ""
		(layer "F.Cu")
		(at 419.48989 -412.090108)
		(property "Reference" "J9"
			(at -5.783834 6.071108 90)
			(unlocked yes)
			(layer "F.SilkS")
			(effects
				(font
					(size 2.032 1.524)
					(thickness 0.1524)
				)
				(justify left)
			)
		)
		(property "Value" ""
			(at 0 0 0)
			(layer "F.Fab")
			(effects
				(font
					(size 1.27 1.27)
				)
			)
		)
		(duplicate_pad_numbers_are_jumpers no)
		(pad "N2_3" thru_hole circle
			(at 4.400042 27.29992 180)
			(size 0.906272 0.906272)
			(drill 0.499872)
			(layers "*.Cu" "*.Mask")
			(remove_unused_layers no)
			(net "GND")
			(clearance 0.0508)
			(thermal_gap 0.0508)
		)
		(pad "N2_5" thru_hole circle
			(at 8.800084 27.29992 180)
			(size 0.906272 0.906272)
			(drill 0.499872)
			(layers "*.Cu" "*.Mask")
			(remove_unused_layers no)
			(net "GND")
			(clearance 0.0508)
			(thermal_gap 0.0508)
		)
		(pad "N2_7" thru_hole circle
			(at 13.199872 27.29992 180)
			(size 0.906272 0.906272)
			(drill 0.499872)
			(layers "*.Cu" "*.Mask")
			(remove_unused_layers no)
			(net "GND")
			(clearance 0.0508)
			(thermal_gap 0.0508)
		)
		(pad "N2_9" thru_hole circle
			(at 17.599914 27.29992 180)
			(size 0.906272 0.906272)
			(drill 0.499872)
			(layers "*.Cu" "*.Mask")
			(remove_unused_layers no)
			(net "GND")
			(clearance 0.0508)
			(thermal_gap 0.0508)
		)
		(pad "N10" thru_hole circle
			(at 19.800062 27.500072 180)
			(size 0.71628 0.71628)
			(drill 0.30988)
			(layers "*.Cu" "*.Mask")
			(remove_unused_layers no)
			(net "Net_8761")
			(clearance 0.0508)
			(thermal_gap 0.0508)
		)
		(pad "O9" thru_hole circle
			(at 17.599914 28.599892 180)
			(size 0.71628 0.71628)
			(drill 0.30988)
			(layers "*.Cu" "*.Mask")
			(remove_unused_layers no)
			(net "Net_8759")
			(clearance 0.0508)
			(thermal_gap 0.0508)
		)
		(pad "O10" thru_hole circle
			(at 19.800062 28.800044 180)
			(size 0.71628 0.71628)
			(drill 0.30988)
			(layers "*.Cu" "*.Mask")
			(remove_unused_layers no)
			(net "Net_8760")
			(clearance 0.0508)
			(thermal_gap 0.0508)
		)
		(pad "P2" thru_hole circle
			(at 2.199894 30.100016 180)
			(size 0.906272 0.906272)
			(drill 0.499872)
			(layers "*.Cu" "*.Mask")
			(remove_unused_layers no)
			(net "GND")
			(clearance 0.0508)
			(thermal_gap 0.0508)
		)
		(pad "P4" thru_hole circle
			(at 6.599936 30.100016 180)
			(size 0.906272 0.906272)
			(drill 0.499872)
			(layers "*.Cu" "*.Mask")
			(remove_unused_layers no)
			(net "GND")
			(clearance 0.0508)
			(thermal_gap 0.0508)
		)
		(pad "P6" thru_hole circle
			(at 10.999978 30.100016 180)
			(size 0.906272 0.906272)
			(drill 0.499872)
			(layers "*.Cu" "*.Mask")
			(remove_unused_layers no)
			(net "GND")
			(clearance 0.0508)
			(thermal_gap 0.0508)
		)
		(pad "P8" thru_hole circle
			(at 15.40002 30.100016 180)
			(size 0.906272 0.906272)
			(drill 0.499872)
			(layers "*.Cu" "*.Mask")
			(remove_unused_layers no)
			(net "GND")
			(clearance 0.0508)
			(thermal_gap 0.0508)
		)
		(pad "P9" thru_hole circle
			(at 17.599914 29.900118 180)
			(size 0.71628 0.71628)
			(drill 0.30988)
			(layers "*.Cu" "*.Mask")
			(remove_unused_layers no)
			(net "Net_8758")
			(clearance 0.0508)
			(thermal_gap 0.0508)
		)
		(pad "P10" thru_hole circle
			(at 19.800062 30.100016 180)
			(size 0.906272 0.906272)
			(drill 0.499872)
			(layers "*.Cu" "*.Mask")
			(remove_unused_layers no)
			(net "GND")
			(clearance 0.0508)
			(thermal_gap 0.0508)
		)
		(pad "Q1" thru_hole circle
			(at 0 31.20009 180)
			(size 0.906272 0.906272)
			(drill 0.499872)
			(layers "*.Cu" "*.Mask")
			(remove_unused_layers no)
			(net "GND")
			(clearance 0.0508)
			(thermal_gap 0.0508)
		)
		(pad "Q3" thru_hole circle
			(at 4.400042 31.20009 180)
			(size 0.906272 0.906272)
			(drill 0.499872)
			(layers "*.Cu" "*.Mask")
			(remove_unused_layers no)
			(net "GND")
			(clearance 0.0508)
			(thermal_gap 0.0508)
		)
		(pad "Q5" thru_hole circle
			(at 8.800084 31.20009 180)
			(size 0.906272 0.906272)
			(drill 0.499872)
			(layers "*.Cu" "*.Mask")
			(remove_unused_layers no)
			(net "GND")
			(clearance 0.0508)
			(thermal_gap 0.0508)
		)
		(pad "Q7" thru_hole circle
			(at 13.199872 31.20009 180)
			(size 0.906272 0.906272)
			(drill 0.499872)
			(layers "*.Cu" "*.Mask")
			(remove_unused_layers no)
			(net "GND")
			(clearance 0.0508)
			(thermal_gap 0.0508)
		)
		(pad "Q9" thru_hole circle
			(at 17.599914 31.20009 180)
			(size 0.906272 0.906272)
			(drill 0.499872)
			(layers "*.Cu" "*.Mask")
			(remove_unused_layers no)
			(net "GND")
			(clearance 0.0508)
			(thermal_gap 0.0508)
		)
		(pad "Q10" thru_hole circle
			(at 19.800062 31.399988 180)
			(size 0.71628 0.71628)
			(drill 0.30988)
			(layers "*.Cu" "*.Mask")
			(remove_unused_layers no)
			(net "Net_8757")
			(clearance 0.0508)
			(thermal_gap 0.0508)
		)
		(pad "R9" thru_hole circle
			(at 17.599914 32.500062 180)
			(size 0.71628 0.71628)
			(drill 0.30988)
			(layers "*.Cu" "*.Mask")
			(remove_unused_layers no)
			(net "Net_8755")
			(clearance 0.0508)
			(thermal_gap 0.0508)
		)
		(pad "R10" thru_hole circle
			(at 19.800062 32.69996 180)
			(size 0.71628 0.71628)
			(drill 0.30988)
			(layers "*.Cu" "*.Mask")
			(remove_unused_layers no)
			(net "Net_8756")
			(clearance 0.0508)
			(thermal_gap 0.0508)
		)
		(pad "S2" thru_hole circle
			(at 2.199894 33.999932 180)
			(size 0.906272 0.906272)
			(drill 0.499872)
			(layers "*.Cu" "*.Mask")
			(remove_unused_layers no)
			(net "GND")
			(clearance 0.0508)
			(thermal_gap 0.0508)
		)
		(pad "S4" thru_hole circle
			(at 6.599936 33.999932 180)
			(size 0.906272 0.906272)
			(drill 0.499872)
			(layers "*.Cu" "*.Mask")
			(remove_unused_layers no)
			(net "GND")
			(clearance 0.0508)
			(thermal_gap 0.0508)
		)
		(pad "S6" thru_hole circle
			(at 10.999978 33.999932 180)
			(size 0.906272 0.906272)
			(drill 0.499872)
			(layers "*.Cu" "*.Mask")
			(remove_unused_layers no)
			(net "GND")
			(clearance 0.0508)
			(thermal_gap 0.0508)
		)
		(pad "S8" thru_hole circle
			(at 15.40002 33.999932 180)
			(size 0.906272 0.906272)
			(drill 0.499872)
			(layers "*.Cu" "*.Mask")
			(remove_unused_layers no)
			(net "GND")
			(clearance 0.0508)
			(thermal_gap 0.0508)
		)
		(pad "S9" thru_hole circle
			(at 17.599914 33.800034 180)
			(size 0.71628 0.71628)
			(drill 0.30988)
			(layers "*.Cu" "*.Mask")
			(remove_unused_layers no)
			(net "Net_8754")
			(clearance 0.0508)
			(thermal_gap 0.0508)
		)
		(pad "S10" thru_hole circle
			(at 19.800062 33.999932 180)
			(size 0.906272 0.906272)
			(drill 0.499872)
			(layers "*.Cu" "*.Mask")
			(remove_unused_layers no)
			(net "GND")
			(clearance 0.0508)
			(thermal_gap 0.0508)
		)
		(pad "T1" thru_hole circle
			(at 0 35.100006 180)
			(size 0.906272 0.906272)
			(drill 0.499872)
			(layers "*.Cu" "*.Mask")
			(remove_unused_layers no)
			(net "GND")
			(clearance 0.0508)
			(thermal_gap 0.0508)
		)
		(pad "T3" thru_hole circle
			(at 4.400042 35.100006 180)
			(size 0.906272 0.906272)
			(drill 0.499872)
			(layers "*.Cu" "*.Mask")
			(remove_unused_layers no)
			(net "GND")
			(clearance 0.0508)
			(thermal_gap 0.0508)
		)
		(pad "T5" thru_hole circle
			(at 8.800084 35.100006 180)
			(size 0.906272 0.906272)
			(drill 0.499872)
			(layers "*.Cu" "*.Mask")
			(remove_unused_layers no)
			(net "GND")
			(clearance 0.0508)
			(thermal_gap 0.0508)
		)
		(pad "T7" thru_hole circle
			(at 13.199872 35.100006 180)
			(size 0.906272 0.906272)
			(drill 0.499872)
			(layers "*.Cu" "*.Mask")
			(remove_unused_layers no)
			(net "GND")
			(clearance 0.0508)
			(thermal_gap 0.0508)
		)
		(pad "T9" thru_hole circle
			(at 17.599914 35.100006 180)
			(size 0.906272 0.906272)
			(drill 0.499872)
			(layers "*.Cu" "*.Mask")
			(remove_unused_layers no)
			(net "GND")
			(clearance 0.0508)
			(thermal_gap 0.0508)
		)
		(pad "T10" thru_hole circle
			(at 19.800062 35.299904 180)
			(size 0.71628 0.71628)
			(drill 0.30988)
			(layers "*.Cu" "*.Mask")
			(remove_unused_layers no)
			(net "Net_8753")
			(clearance 0.0508)
			(thermal_gap 0.0508)
		)
		(pad "U9" thru_hole circle
			(at 17.599914 36.399978 180)
			(size 0.71628 0.71628)
			(drill 0.30988)
			(layers "*.Cu" "*.Mask")
			(remove_unused_layers no)
			(net "Net_8751")
			(clearance 0.0508)
			(thermal_gap 0.0508)
		)
		(pad "U10" thru_hole circle
			(at 19.800062 36.599876 180)
			(size 0.71628 0.71628)
			(drill 0.30988)
			(layers "*.Cu" "*.Mask")
			(remove_unused_layers no)
			(net "Net_8752")
			(clearance 0.0508)
			(thermal_gap 0.0508)
		)
		(pad "V2" thru_hole circle
			(at 2.199894 37.900102 180)
			(size 0.906272 0.906272)
			(drill 0.499872)
			(layers "*.Cu" "*.Mask")
			(remove_unused_layers no)
			(net "GND")
			(clearance 0.0508)
			(thermal_gap 0.0508)
		)
		(pad "V4" thru_hole circle
			(at 6.599936 37.900102 180)
			(size 0.906272 0.906272)
			(drill 0.499872)
			(layers "*.Cu" "*.Mask")
			(remove_unused_layers no)
			(net "GND")
			(clearance 0.0508)
			(thermal_gap 0.0508)
		)
		(pad "V6" thru_hole circle
			(at 10.999978 37.900102 180)
			(size 0.906272 0.906272)
			(drill 0.499872)
			(layers "*.Cu" "*.Mask")
			(remove_unused_layers no)
			(net "GND")
			(clearance 0.0508)
			(thermal_gap 0.0508)
		)
		(pad "V8" thru_hole circle
			(at 15.40002 37.900102 180)
			(size 0.906272 0.906272)
			(drill 0.499872)
			(layers "*.Cu" "*.Mask")
			(remove_unused_layers no)
			(net "GND")
			(clearance 0.0508)
			(thermal_gap 0.0508)
		)
		(pad "V9" thru_hole circle
			(at 17.599914 37.69995 180)
			(size 0.71628 0.71628)
			(drill 0.30988)
			(layers "*.Cu" "*.Mask")
			(remove_unused_layers no)
			(net "Net_8750")
			(clearance 0.0508)
			(thermal_gap 0.0508)
		)
		(pad "V10" thru_hole circle
			(at 19.800062 37.900102 180)
			(size 0.906272 0.906272)
			(drill 0.499872)
			(layers "*.Cu" "*.Mask")
			(remove_unused_layers no)
			(net "GND")
			(clearance 0.0508)
			(thermal_gap 0.0508)
		)
		(pad "W1" thru_hole circle
			(at 0 38.999922 180)
			(size 0.906272 0.906272)
			(drill 0.499872)
			(layers "*.Cu" "*.Mask")
			(remove_unused_layers no)
			(net "GND")
			(clearance 0.0508)
			(thermal_gap 0.0508)
		)
		(pad "W3" thru_hole circle
			(at 4.400042 38.999922 180)
			(size 0.906272 0.906272)
			(drill 0.499872)
			(layers "*.Cu" "*.Mask")
			(remove_unused_layers no)
			(net "GND")
			(clearance 0.0508)
			(thermal_gap 0.0508)
		)
		(pad "W5" thru_hole circle
			(at 8.800084 38.999922 180)
			(size 0.906272 0.906272)
			(drill 0.499872)
			(layers "*.Cu" "*.Mask")
			(remove_unused_layers no)
			(net "GND")
			(clearance 0.0508)
			(thermal_gap 0.0508)
		)
		(pad "W7" thru_hole circle
			(at 13.199872 38.999922 180)
			(size 0.906272 0.906272)
			(drill 0.499872)
			(layers "*.Cu" "*.Mask")
			(remove_unused_layers no)
			(net "GND")
			(clearance 0.0508)
			(thermal_gap 0.0508)
		)
		(pad "W9" thru_hole circle
			(at 17.599914 38.999922 180)
			(size 0.906272 0.906272)
			(drill 0.499872)
			(layers "*.Cu" "*.Mask")
			(remove_unused_layers no)
			(net "GND")
			(clearance 0.0508)
			(thermal_gap 0.0508)
		)
		(pad "W10" thru_hole circle
			(at 19.800062 39.200074 180)
			(size 0.71628 0.71628)
			(drill 0.30988)
			(layers "*.Cu" "*.Mask")
			(remove_unused_layers no)
			(net "Net_8749")
			(clearance 0.0508)
			(thermal_gap 0.0508)
		)
		(pad "X9" thru_hole circle
			(at 17.599914 40.299894 180)
			(size 0.71628 0.71628)
			(drill 0.30988)
			(layers "*.Cu" "*.Mask")
			(remove_unused_layers no)
			(net "Net_8747")
			(clearance 0.0508)
			(thermal_gap 0.0508)
		)
		(pad "X10" thru_hole circle
			(at 19.800062 40.500046 180)
			(size 0.71628 0.71628)
			(drill 0.30988)
			(layers "*.Cu" "*.Mask")
			(remove_unused_layers no)
			(net "Net_8748")
			(clearance 0.0508)
			(thermal_gap 0.0508)
		)
		(pad "Y2" thru_hole circle
			(at 2.199894 41.800018 180)
			(size 0.906272 0.906272)
			(drill 0.499872)
			(layers "*.Cu" "*.Mask")
			(remove_unused_layers no)
			(net "GND")
			(clearance 0.0508)
			(thermal_gap 0.0508)
		)
		(pad "Y4" thru_hole circle
			(at 6.599936 41.800018 180)
			(size 0.906272 0.906272)
			(drill 0.499872)
			(layers "*.Cu" "*.Mask")
			(remove_unused_layers no)
			(net "GND")
			(clearance 0.0508)
			(thermal_gap 0.0508)
		)
		(pad "Y6" thru_hole circle
			(at 10.999978 41.800018 180)
			(size 0.906272 0.906272)
			(drill 0.499872)
			(layers "*.Cu" "*.Mask")
			(remove_unused_layers no)
			(net "GND")
			(clearance 0.0508)
			(thermal_gap 0.0508)
		)
		(pad "Y8" thru_hole circle
			(at 15.40002 41.800018 180)
			(size 0.906272 0.906272)
			(drill 0.499872)
			(layers "*.Cu" "*.Mask")
			(remove_unused_layers no)
			(net "GND")
			(clearance 0.0508)
			(thermal_gap 0.0508)
		)
		(pad "Y9" thru_hole circle
			(at 17.599914 41.60012 180)
			(size 0.71628 0.71628)
			(drill 0.30988)
			(layers "*.Cu" "*.Mask")
			(remove_unused_layers no)
			(net "Net_8746")
			(clearance 0.0508)
			(thermal_gap 0.0508)
		)
		(pad "Y10" thru_hole circle
			(at 19.800062 41.800018 180)
			(size 0.906272 0.906272)
			(drill 0.499872)
			(layers "*.Cu" "*.Mask")
			(remove_unused_layers no)
			(net "GND")
			(clearance 0.0508)
			(thermal_gap 0.0508)
		)
		(pad "Z1" thru_hole circle
			(at 0 42.900092 180)
			(size 0.906272 0.906272)
			(drill 0.499872)
			(layers "*.Cu" "*.Mask")
			(remove_unused_layers no)
			(net "GND")
			(clearance 0.0508)
			(thermal_gap 0.0508)
		)
		(pad "Z2" thru_hole circle
			(at 2.199894 43.09999 180)
			(size 0.71628 0.71628)
			(drill 0.30988)
			(layers "*.Cu" "*.Mask")
			(remove_unused_layers no)
			(net "Net_8780")
			(clearance 0.0508)
			(thermal_gap 0.0508)
		)
		(pad "Z3" thru_hole circle
			(at 4.400042 42.900092 180)
			(size 0.906272 0.906272)
			(drill 0.499872)
			(layers "*.Cu" "*.Mask")
			(remove_unused_layers no)
			(net "GND")
			(clearance 0.0508)
			(thermal_gap 0.0508)
		)
		(pad "Z4" thru_hole circle
			(at 6.599936 43.09999 180)
			(size 0.71628 0.71628)
			(drill 0.30988)
			(layers "*.Cu" "*.Mask")
			(remove_unused_layers no)
			(net "Net_8778")
			(clearance 0.0508)
			(thermal_gap 0.0508)
		)
		(pad "Z5" thru_hole circle
			(at 8.800084 42.900092 180)
			(size 0.906272 0.906272)
			(drill 0.499872)
			(layers "*.Cu" "*.Mask")
			(remove_unused_layers no)
			(net "GND")
			(clearance 0.0508)
			(thermal_gap 0.0508)
		)
		(pad "Z6" thru_hole circle
			(at 10.999978 43.09999 180)
			(size 0.71628 0.71628)
			(drill 0.30988)
			(layers "*.Cu" "*.Mask")
			(remove_unused_layers no)
			(net "Net_8776")
			(clearance 0.0508)
			(thermal_gap 0.0508)
		)
		(pad "Z7" thru_hole circle
			(at 13.199872 42.900092 180)
			(size 0.906272 0.906272)
			(drill 0.499872)
			(layers "*.Cu" "*.Mask")
			(remove_unused_layers no)
			(net "GND")
			(clearance 0.0508)
			(thermal_gap 0.0508)
		)
		(pad "Z8" thru_hole circle
			(at 15.40002 43.09999 180)
			(size 0.71628 0.71628)
			(drill 0.30988)
			(layers "*.Cu" "*.Mask")
			(remove_unused_layers no)
			(net "Net_8775")
			(clearance 0.0508)
			(thermal_gap 0.0508)
		)
		(pad "Z9" thru_hole circle
			(at 17.599914 42.900092 180)
			(size 0.906272 0.906272)
			(drill 0.499872)
			(layers "*.Cu" "*.Mask")
			(remove_unused_layers no)
			(net "GND")
			(clearance 0.0508)
			(thermal_gap 0.0508)
		)
		(pad "Z10" thru_hole circle
			(at 19.800062 43.09999 180)
			(size 0.71628 0.71628)
			(drill 0.30988)
			(layers "*.Cu" "*.Mask")
			(remove_unused_layers no)
			(net "Net_8745")
			(clearance 0.0508)
			(thermal_gap 0.0508)
		)
	)
)
